#ISCELL
  logical_power cad_note *
  *
#ISCELL
  pure_quanta quanta_title_block_c *
  *
#CELL
  pure_quanta q_cap *
  page199_i19
#CELL
  pure_quanta q_inductor *
  page199_i20
#ISCELL
  logical_power universal_power *
  page199_i21
#ISCELL
  logical_power universal_power *
  page199_i3
#ISCELL
  logical_power universal_power *
  page199_i31
#ISCELL
  logical_power universal_power *
  page199_i35
#CELL
  pure_quanta q_res *
  page199_i36
#CELL
  pure_quanta q_inductor *
  page199_i41
#ISCELL
  logical_power universal_power *
  page199_i42
#CELL
  pure_quanta q_cap *
  page199_i43
#CELL
  pure_quanta q_cap *
  page199_i44
#CELL
  pure_quanta q_cap *
  page199_i48
#ISCELL
  logical_power universal_power *
  page199_i51
#CELL
  pure_quanta q_cap *
  page199_i53
#CELL
  pure_quanta q_res *
  page199_i55
#ISCELL
  logical_power universal_power *
  page199_i56
#CELL
  pure_quanta q_cap *
  page199_i58
#CELL
  pure_quanta q_cap *
  page199_i59
#CELL
  pure_quanta q_cap *
  page199_i6
#CELL
  pure_quanta q_inductor *
  page199_i60
#ISCELL
  logical_power universal_power *
  page199_i61
#ISCELL
  logical_power universal_gnd *
  page199_i69
#CELL
  pure_quanta q_res *
  page199_i7
#ISCELL
  logical_power universal_gnd *
  page199_i70
#ISCELL
  logical_power universal_gnd *
  page199_i71
#ISCELL
  logical_power universal_gnd *
  page199_i72
#ISCELL
  logical_power universal_gnd *
  page199_i73
#ISCELL
  logical_power universal_gnd *
  page199_i74
#CELL
  pure_quanta q_cap *
  page199_i76
#CELL
  pure_quanta q_cap *
  page199_i77
#CELL
  pure_quanta q_cap *
  page199_i78
#CELL
  pure_quanta q_cap *
  page199_i79
#ISCELL
  logical_power universal_power *
  page199_i8
#CELL
  pure_quanta q_cap *
  page199_i80
#CELL
  pure_quanta q_cap *
  page199_i81
#CELL
  pure_quanta q_cap *
  page199_i82
#CELL
  pure_quanta q_cap *
  page199_i85
#CELL
  pure_quanta q_cap *
  page199_i86
#CELL
  pure_quanta q_cap *
  page199_i87
#CELL
  pure_quanta q_cap *
  page199_i88
#CELL
  pure_quanta q_cap *
  page199_i89
